(kicad_pcb
	(version 20260206)
	(generator "pcbnew")
	(generator_version "10.0")
	(general
		(thickness 1.6)
		(legacy_teardrops no)
	)
	(paper "A4")
	(title_block
		(title "Bryce Canyon_IOM_IOC_16318-2_OCP.brd")
		(comment 1 "Bryce Canyon / footprints 202-209 of 1605")
	)
	(layers
		(0 "F.Cu" signal "TOP")
		(4 "In1.Cu" signal "L2GND")
		(6 "In2.Cu" signal "L3")
		(8 "In3.Cu" signal "L4VCC")
		(10 "In4.Cu" signal "L5VCC")
		(12 "In5.Cu" signal "L6")
		(14 "In6.Cu" signal "L7GND")
		(2 "B.Cu" signal "BOTTOM")
		(9 "F.Adhes" user "F.Adhesive")
		(11 "B.Adhes" user "B.Adhesive")
		(13 "F.Paste" user "Package Geometry/Pastemask Top")
		(15 "B.Paste" user "Package Geometry/Pastemask Bottom")
		(5 "F.SilkS" user "Ref Des/Silkscreen Top")
		(7 "B.SilkS" user "Ref Des/Silkscreen Bottom")
		(1 "F.Mask" user "Board Geometry/Soldermask Top")
		(3 "B.Mask" user "Board Geometry/Soldermask Bottom")
		(17 "Dwgs.User" user "User.Drawings")
		(19 "Cmts.User" user "User.Comments")
		(21 "Eco1.User" user "User.Eco1")
		(23 "Eco2.User" user "User.Eco2")
		(25 "Edge.Cuts" user "Board Geometry/Outline")
		(27 "Margin" user)
		(31 "F.CrtYd" user "Package Geometry/Place Bound Top")
		(29 "B.CrtYd" user "Package Geometry/Place Bound Bottom")
		(35 "F.Fab" user "Ref Des/Assembly Top")
		(33 "B.Fab" user "Ref Des/Assembly Bottom")
	)
	(footprint ""
		(layer "F.Cu")
		(at 125.85446 -16.17218 90)
		(property "Reference" "PQ1"
			(at 0 0 90)
			(layer "F.SilkS")
			(hide yes)
			(effects
				(font
					(size 1.27 1.27)
				)
			)
		)
		(property "Value" "MMBT3904-3-GP"
			(at 0.10287 -10.29843 90)
			(unlocked yes)
			(layer "F.Fab")
			(hide yes)
			(effects
				(font
					(size 1.016 1.016)
					(thickness 0.1524)
				)
			)
		)
		(property "Device Type" "SOT23CBE2D4H44"
			(at 0.10287 -12.20343 90)
			(unlocked yes)
			(layer "F.Fab")
			(hide yes)
			(effects
				(font
					(size 1.016 1.016)
					(thickness 0.1524)
				)
			)
		)
		(duplicate_pad_numbers_are_jumpers no)
		(fp_line
			(start 1.651 -1.778)
			(end -1.651 -1.778)
			(stroke
				(width 0.1524)
				(type default)
			)
			(layer "F.SilkS")
		)
		(fp_line
			(start -1.651 -1.778)
			(end -1.651 1.778)
			(stroke
				(width 0.1524)
				(type default)
			)
			(layer "F.SilkS")
		)
		(fp_line
			(start 1.651 1.778)
			(end 1.651 -1.778)
			(stroke
				(width 0.1524)
				(type default)
			)
			(layer "F.SilkS")
		)
		(fp_line
			(start -1.651 1.778)
			(end 1.651 1.778)
			(stroke
				(width 0.1524)
				(type default)
			)
			(layer "F.SilkS")
		)
		(fp_poly
			(pts
				(xy -1.778 1.8796) (xy -1.778 -1.8796) (xy 1.778 -1.8796) (xy 1.778 1.8796)
			)
			(stroke
				(width 0)
				(type default)
			)
			(fill no)
			(layer "F.CrtYd")
		)
		(fp_poly
			(pts
				(xy -1.778 1.8796) (xy -1.778 -1.8796) (xy 1.778 -1.8796) (xy 1.778 1.8796)
			)
			(stroke
				(width 0)
				(type default)
			)
			(fill no)
			(layer "F.Fab")
		)
		(pad "B" smd custom
			(at -0.98425 0.9525 90)
			(size 0.1905 0.1905)
			(layers "F.Cu" "F.Mask" "F.Paste")
			(net "MB0_TEMP_C")
			(options
				(clearance outline)
				(anchor circle)
			)
			(primitives
				(gr_poly
					(pts
						(arc
							(start -0.1778 0.5715)
							(mid -0.321484 0.511984)
							(end -0.381 0.3683)
						)
						(arc
							(start -0.381 -0.3683)
							(mid -0.321484 -0.511984)
							(end -0.1778 -0.5715)
						)
						(arc
							(start 0.1778 -0.5715)
							(mid 0.321484 -0.511984)
							(end 0.381 -0.3683)
						)
						(arc
							(start 0.381 0.3683)
							(mid 0.321484 0.511984)
							(end 0.1778 0.5715)
						)
					)
					(width 0)
					(fill yes)
				)
			)
		)
		(pad "C" smd custom
			(at 0 -0.9525 90)
			(size 0.1905 0.1905)
			(layers "F.Cu" "F.Mask" "F.Paste")
			(net "MB0_TEMP_C")
			(options
				(clearance outline)
				(anchor circle)
			)
			(primitives
				(gr_poly
					(pts
						(arc
							(start -0.1778 0.5715)
							(mid -0.321484 0.511984)
							(end -0.381 0.3683)
						)
						(arc
							(start -0.381 -0.3683)
							(mid -0.321484 -0.511984)
							(end -0.1778 -0.5715)
						)
						(arc
							(start 0.1778 -0.5715)
							(mid 0.321484 -0.511984)
							(end 0.381 -0.3683)
						)
						(arc
							(start 0.381 0.3683)
							(mid 0.321484 0.511984)
							(end 0.1778 0.5715)
						)
					)
					(width 0)
					(fill yes)
				)
			)
		)
		(pad "E" smd custom
			(at 0.98425 0.9525 90)
			(size 0.1905 0.1905)
			(layers "F.Cu" "F.Mask" "F.Paste")
			(net "MB0_TEMP_E")
			(options
				(clearance outline)
				(anchor circle)
			)
			(primitives
				(gr_poly
					(pts
						(arc
							(start -0.1778 0.5715)
							(mid -0.321484 0.511984)
							(end -0.381 0.3683)
						)
						(arc
							(start -0.381 -0.3683)
							(mid -0.321484 -0.511984)
							(end -0.1778 -0.5715)
						)
						(arc
							(start 0.1778 -0.5715)
							(mid 0.321484 -0.511984)
							(end 0.381 -0.3683)
						)
						(arc
							(start 0.381 0.3683)
							(mid 0.321484 0.511984)
							(end 0.1778 0.5715)
						)
					)
					(width 0)
					(fill yes)
				)
			)
		)
	)
	(footprint ""
		(layer "F.Cu")
		(at 192.64249 -105.784142)
		(property "Reference" "C264"
			(at 0 0 0)
			(layer "F.SilkS")
			(hide yes)
			(effects
				(font
					(size 1.27 1.27)
				)
			)
		)
		(property "Value" "SC22U6D3V6KX-2-GP"
			(at -0.0762 -5.1308 0)
			(unlocked yes)
			(layer "F.Fab")
			(hide yes)
			(effects
				(font
					(size 1.016 1.016)
					(thickness 0.1524)
				)
			)
		)
		(property "Device Type" "C1206H71"
			(at -0.127 -6.6548 0)
			(unlocked yes)
			(layer "F.Fab")
			(hide yes)
			(effects
				(font
					(size 1.016 1.016)
					(thickness 0.1524)
				)
			)
		)
		(duplicate_pad_numbers_are_jumpers no)
		(fp_line
			(start -1.016 -2.2352)
			(end 1.016 -2.2352)
			(stroke
				(width 0.1524)
				(type default)
			)
			(layer "F.SilkS")
		)
		(fp_line
			(start -1.016 -0.8382)
			(end -1.016 -2.2352)
			(stroke
				(width 0.1524)
				(type default)
			)
			(layer "F.SilkS")
		)
		(fp_line
			(start -1.016 2.2352)
			(end -1.016 0.8382)
			(stroke
				(width 0.1524)
				(type default)
			)
			(layer "F.SilkS")
		)
		(fp_line
			(start 1.016 -2.2352)
			(end 1.016 -0.8382)
			(stroke
				(width 0.1524)
				(type default)
			)
			(layer "F.SilkS")
		)
		(fp_line
			(start 1.016 0.8382)
			(end 1.016 2.2352)
			(stroke
				(width 0.1524)
				(type default)
			)
			(layer "F.SilkS")
		)
		(fp_line
			(start 1.016 2.2352)
			(end -1.016 2.2352)
			(stroke
				(width 0.1524)
				(type default)
			)
			(layer "F.SilkS")
		)
		(fp_rect
			(start -1.0922 2.3114)
			(end 1.0922 -2.3114)
			(stroke
				(width 0)
				(type default)
			)
			(fill no)
			(layer "F.CrtYd")
		)
		(fp_poly
			(pts
				(xy 1.0922 -2.3114) (xy 1.0922 2.3114) (xy -1.0922 2.3114) (xy -1.0922 -2.3114)
			)
			(stroke
				(width 0)
				(type default)
			)
			(fill no)
			(layer "F.Fab")
		)
		(pad "1" smd rect
			(at 0 -1.397)
			(size 1.651 1.27)
			(layers "F.Cu" "F.Mask" "F.Paste")
			(net "P0V975")
		)
		(pad "2" smd rect
			(at 0 1.397)
			(size 1.651 1.27)
			(layers "F.Cu" "F.Mask" "F.Paste")
			(net "GND")
		)
	)
	(footprint ""
		(layer "F.Cu")
		(at 67.447414 -138.114786 -90)
		(property "Reference" "R59"
			(at 0 0 270)
			(layer "F.SilkS")
			(hide yes)
			(effects
				(font
					(size 1.27 1.27)
				)
			)
		)
		(property "Value" "33R2F-3-GP"
			(at 0.064008 -3.993896 270)
			(unlocked yes)
			(layer "F.Fab")
			(hide yes)
			(effects
				(font
					(size 1.016 1.016)
					(thickness 0.1524)
				)
			)
		)
		(property "Device Type" "R402H16"
			(at 0.064008 -5.517896 270)
			(unlocked yes)
			(layer "F.Fab")
			(hide yes)
			(effects
				(font
					(size 1.016 1.016)
					(thickness 0.1524)
				)
			)
		)
		(duplicate_pad_numbers_are_jumpers no)
		(fp_line
			(start -0.508 -0.9398)
			(end -0.508 0.9398)
			(stroke
				(width 0.1524)
				(type default)
			)
			(layer "F.SilkS")
		)
		(fp_line
			(start 0.508 -0.9398)
			(end -0.508 -0.9398)
			(stroke
				(width 0.1524)
				(type default)
			)
			(layer "F.SilkS")
		)
		(fp_rect
			(start -0.508 0.9398)
			(end 0.508 -0.9398)
			(stroke
				(width 0)
				(type default)
			)
			(fill no)
			(layer "F.CrtYd")
		)
		(fp_rect
			(start -0.508 0.9398)
			(end 0.508 -0.9398)
			(stroke
				(width 0)
				(type default)
			)
			(fill no)
			(layer "F.Fab")
		)
		(pad "1" smd custom
			(at 0 -0.4445 270)
			(size 0.1397 0.1397)
			(layers "F.Cu" "F.Mask" "F.Paste")
			(net "FP_RETBTN")
			(options
				(clearance outline)
				(anchor circle)
			)
			(primitives
				(gr_poly
					(pts
						(arc
							(start -0.1778 -0.2794)
							(mid -0.249642 -0.249642)
							(end -0.2794 -0.1778)
						)
						(arc
							(start -0.2794 0.1778)
							(mid -0.249642 0.249642)
							(end -0.1778 0.2794)
						)
						(arc
							(start 0.1778 0.2794)
							(mid 0.249642 0.249642)
							(end 0.2794 0.1778)
						)
						(arc
							(start 0.2794 -0.1778)
							(mid 0.249642 -0.249642)
							(end 0.1778 -0.2794)
						)
					)
					(width 0)
					(fill yes)
				)
			)
		)
		(pad "2" smd custom
			(at 0 0.4445 270)
			(size 0.1397 0.1397)
			(layers "F.Cu" "F.Mask" "F.Paste")
			(net "RSTBTN_OUT_N")
			(options
				(clearance outline)
				(anchor circle)
			)
			(primitives
				(gr_poly
					(pts
						(arc
							(start -0.1778 -0.2794)
							(mid -0.249642 -0.249642)
							(end -0.2794 -0.1778)
						)
						(arc
							(start -0.2794 0.1778)
							(mid -0.249642 0.249642)
							(end -0.1778 0.2794)
						)
						(arc
							(start 0.1778 0.2794)
							(mid 0.249642 0.249642)
							(end 0.2794 0.1778)
						)
						(arc
							(start 0.2794 -0.1778)
							(mid 0.249642 -0.249642)
							(end 0.1778 -0.2794)
						)
					)
					(width 0)
					(fill yes)
				)
			)
		)
	)
	(footprint ""
		(layer "F.Cu")
		(at 69.5452 -175.1584 180)
		(property "Reference" "U31"
			(at 0 0 180)
			(layer "F.SilkS")
			(hide yes)
			(effects
				(font
					(size 1.27 1.27)
				)
			)
		)
		(property "Value" "SN74LVC1G08DCKR-GP"
			(at -2.3368 -8.6868 180)
			(unlocked yes)
			(layer "F.Fab")
			(hide yes)
			(effects
				(font
					(size 1.016 1.016)
					(thickness 0.1524)
				)
			)
		)
		(property "Device Type" "SC70-5H44"
			(at -2.3114 -10.414 180)
			(unlocked yes)
			(layer "F.Fab")
			(hide yes)
			(effects
				(font
					(size 1.016 1.016)
					(thickness 0.1524)
				)
			)
		)
		(duplicate_pad_numbers_are_jumpers no)
		(fp_line
			(start 1.3843 -1.8034)
			(end 1.3843 -1.1176)
			(stroke
				(width 0.3302)
				(type default)
			)
			(layer "F.SilkS")
		)
		(fp_line
			(start 1.27 1.7018)
			(end -1.27 1.7018)
			(stroke
				(width 0.1524)
				(type default)
			)
			(layer "F.SilkS")
		)
		(fp_line
			(start 1.27 -1.7018)
			(end 1.27 1.7018)
			(stroke
				(width 0.1524)
				(type default)
			)
			(layer "F.SilkS")
		)
		(fp_line
			(start 0.6604 -1.8034)
			(end 1.3843 -1.8034)
			(stroke
				(width 0.3302)
				(type default)
			)
			(layer "F.SilkS")
		)
		(fp_line
			(start -1.27 1.7018)
			(end -1.27 -1.7018)
			(stroke
				(width 0.1524)
				(type default)
			)
			(layer "F.SilkS")
		)
		(fp_line
			(start -1.27 -1.7018)
			(end 1.27 -1.7018)
			(stroke
				(width 0.1524)
				(type default)
			)
			(layer "F.SilkS")
		)
		(fp_rect
			(start -1.524 1.9558)
			(end 1.524 -1.9558)
			(stroke
				(width 0)
				(type default)
			)
			(fill no)
			(layer "F.CrtYd")
		)
		(fp_poly
			(pts
				(xy -1.524 -1.9558) (xy 1.524 -1.9558) (xy 1.524 1.9558) (xy -1.524 1.9558)
			)
			(stroke
				(width 0)
				(type default)
			)
			(fill no)
			(layer "F.Fab")
		)
		(pad "1" smd rect
			(at 0.65024 -0.8255 180)
			(size 0.4064 1.2192)
			(layers "F.Cu" "F.Mask" "F.Paste")
			(net "COMP_TO_BMC_RESET_N_OUT")
		)
		(pad "2" smd rect
			(at 0 -0.8255 180)
			(size 0.4064 1.2192)
			(layers "F.Cu" "F.Mask" "F.Paste")
			(net "BMC_TPM_RST_N")
		)
		(pad "3" smd rect
			(at -0.65024 -0.8255 180)
			(size 0.4064 1.2192)
			(layers "F.Cu" "F.Mask" "F.Paste")
			(net "GND")
		)
		(pad "4" smd rect
			(at -0.65024 0.8255 180)
			(size 0.4064 1.2192)
			(layers "F.Cu" "F.Mask" "F.Paste")
			(net "RST_BMC_EXTRST_N_1")
		)
		(pad "5" smd rect
			(at 0.65024 0.8255 180)
			(size 0.4064 1.2192)
			(layers "F.Cu" "F.Mask" "F.Paste")
			(net "P3V3_STBY")
		)
	)
	(footprint ""
		(layer "F.Cu")
		(at 183.515 -86.614)
		(property "Reference" "TP146"
			(at 0 0 0)
			(layer "F.SilkS")
			(hide yes)
			(effects
				(font
					(size 1.27 1.27)
				)
			)
		)
		(property "Value" "TPAD28-2-GP"
			(at -0.0127 -1.6637 0)
			(unlocked yes)
			(layer "F.Fab")
			(hide yes)
			(effects
				(font
					(size 1.016 1.016)
					(thickness 0.1524)
				)
			)
		)
		(property "Device Type" "TPAD28"
			(at -0.0127 -3.1877 0)
			(unlocked yes)
			(layer "F.Fab")
			(hide yes)
			(effects
				(font
					(size 1.016 1.016)
					(thickness 0.1524)
				)
			)
		)
		(duplicate_pad_numbers_are_jumpers no)
		(fp_poly
			(pts
				(arc
					(start 0.3556 0)
					(mid -0.3556 0)
					(end 0.3556 0)
				)
			)
			(stroke
				(width 0)
				(type default)
			)
			(fill no)
			(layer "F.CrtYd")
		)
		(fp_poly
			(pts
				(arc
					(start 0.6096 0)
					(mid -0.6096 0)
					(end 0.6096 0)
				)
			)
			(stroke
				(width 0)
				(type default)
			)
			(fill no)
			(layer "F.Fab")
		)
		(pad "1" smd circle
			(at 0 0)
			(size 0.7112 0.7112)
			(layers "F.Cu" "F.Mask" "F.Paste")
			(net "SYS_HALT0#")
		)
	)
	(footprint ""
		(layer "F.Cu")
		(at 59.817 -139.2428)
		(property "Reference" "TP77"
			(at 0 0 0)
			(layer "F.SilkS")
			(hide yes)
			(effects
				(font
					(size 1.27 1.27)
				)
			)
		)
		(property "Value" "TPAD28-2-GP"
			(at -0.0127 -1.6637 0)
			(unlocked yes)
			(layer "F.Fab")
			(hide yes)
			(effects
				(font
					(size 1.016 1.016)
					(thickness 0.1524)
				)
			)
		)
		(property "Device Type" "TPAD28"
			(at -0.0127 -3.1877 0)
			(unlocked yes)
			(layer "F.Fab")
			(hide yes)
			(effects
				(font
					(size 1.016 1.016)
					(thickness 0.1524)
				)
			)
		)
		(duplicate_pad_numbers_are_jumpers no)
		(fp_poly
			(pts
				(arc
					(start 0.3556 0)
					(mid -0.3556 0)
					(end 0.3556 0)
				)
			)
			(stroke
				(width 0)
				(type default)
			)
			(fill no)
			(layer "F.CrtYd")
		)
		(fp_poly
			(pts
				(arc
					(start 0.6096 0)
					(mid -0.6096 0)
					(end 0.6096 0)
				)
			)
			(stroke
				(width 0)
				(type default)
			)
			(fill no)
			(layer "F.Fab")
		)
		(pad "1" smd circle
			(at 0 0)
			(size 0.7112 0.7112)
			(layers "F.Cu" "F.Mask" "F.Paste")
			(net "TP_BMC_GPIOI7")
		)
	)
	(footprint ""
		(layer "F.Cu")
		(at 61.294772 -144.480534 -90)
		(property "Reference" "R160"
			(at 0 0 270)
			(layer "F.SilkS")
			(hide yes)
			(effects
				(font
					(size 1.27 1.27)
				)
			)
		)
		(property "Value" "0R2J-2-GP"
			(at 0.064008 -3.993896 270)
			(unlocked yes)
			(layer "F.Fab")
			(hide yes)
			(effects
				(font
					(size 1.016 1.016)
					(thickness 0.1524)
				)
			)
		)
		(property "Device Type" "R402H16"
			(at 0.064008 -5.517896 270)
			(unlocked yes)
			(layer "F.Fab")
			(hide yes)
			(effects
				(font
					(size 1.016 1.016)
					(thickness 0.1524)
				)
			)
		)
		(duplicate_pad_numbers_are_jumpers no)
		(fp_line
			(start -0.508 -0.9398)
			(end -0.508 0.9398)
			(stroke
				(width 0.1524)
				(type default)
			)
			(layer "F.SilkS")
		)
		(fp_line
			(start 0.508 -0.9398)
			(end -0.508 -0.9398)
			(stroke
				(width 0.1524)
				(type default)
			)
			(layer "F.SilkS")
		)
		(fp_rect
			(start -0.508 0.9398)
			(end 0.508 -0.9398)
			(stroke
				(width 0)
				(type default)
			)
			(fill no)
			(layer "F.CrtYd")
		)
		(fp_rect
			(start -0.508 0.9398)
			(end 0.508 -0.9398)
			(stroke
				(width 0)
				(type default)
			)
			(fill no)
			(layer "F.Fab")
		)
		(pad "1" smd custom
			(at 0 -0.4445 270)
			(size 0.1397 0.1397)
			(layers "F.Cu" "F.Mask" "F.Paste")
			(net "I2C_SCC_SCL_OUT")
			(options
				(clearance outline)
				(anchor circle)
			)
			(primitives
				(gr_poly
					(pts
						(arc
							(start -0.1778 -0.2794)
							(mid -0.249642 -0.249642)
							(end -0.2794 -0.1778)
						)
						(arc
							(start -0.2794 0.1778)
							(mid -0.249642 0.249642)
							(end -0.1778 0.2794)
						)
						(arc
							(start 0.1778 0.2794)
							(mid 0.249642 0.249642)
							(end 0.2794 0.1778)
						)
						(arc
							(start 0.2794 -0.1778)
							(mid 0.249642 -0.249642)
							(end 0.1778 -0.2794)
						)
					)
					(width 0)
					(fill yes)
				)
			)
		)
		(pad "2" smd custom
			(at 0 0.4445 270)
			(size 0.1397 0.1397)
			(layers "F.Cu" "F.Mask" "F.Paste")
			(net "BMC_SMB3_CLK")
			(options
				(clearance outline)
				(anchor circle)
			)
			(primitives
				(gr_poly
					(pts
						(arc
							(start -0.1778 -0.2794)
							(mid -0.249642 -0.249642)
							(end -0.2794 -0.1778)
						)
						(arc
							(start -0.2794 0.1778)
							(mid -0.249642 0.249642)
							(end -0.1778 0.2794)
						)
						(arc
							(start 0.1778 0.2794)
							(mid 0.249642 0.249642)
							(end 0.2794 0.1778)
						)
						(arc
							(start 0.2794 -0.1778)
							(mid 0.249642 -0.249642)
							(end 0.1778 -0.2794)
						)
					)
					(width 0)
					(fill yes)
				)
			)
		)
	)
	(footprint ""
		(layer "F.Cu")
		(at 60.375546 -187.438538 -90)
		(property "Reference" "R479"
			(at 0 0 270)
			(layer "F.SilkS")
			(hide yes)
			(effects
				(font
					(size 1.27 1.27)
				)
			)
		)
		(property "Value" "0R6J-3-GP"
			(at -0.0508 -4.8514 270)
			(unlocked yes)
			(layer "F.Fab")
			(hide yes)
			(effects
				(font
					(size 1.016 1.016)
					(thickness 0.1524)
				)
			)
		)
		(property "Device Type" "R1206H28"
			(at 0 -6.3754 270)
			(unlocked yes)
			(layer "F.Fab")
			(hide yes)
			(effects
				(font
					(size 1.016 1.016)
					(thickness 0.1524)
				)
			)
		)
		(duplicate_pad_numbers_are_jumpers no)
		(fp_line
			(start -1.016 2.2352)
			(end -1.016 -2.2352)
			(stroke
				(width 0.1524)
				(type default)
			)
			(layer "F.SilkS")
		)
		(fp_line
			(start 1.016 2.2352)
			(end -1.016 2.2352)
			(stroke
				(width 0.1524)
				(type default)
			)
			(layer "F.SilkS")
		)
		(fp_line
			(start -1.016 -2.2352)
			(end 1.016 -2.2352)
			(stroke
				(width 0.1524)
				(type default)
			)
			(layer "F.SilkS")
		)
		(fp_line
			(start 1.016 -2.2352)
			(end 1.016 2.2352)
			(stroke
				(width 0.1524)
				(type default)
			)
			(layer "F.SilkS")
		)
		(fp_rect
			(start -1.0922 2.3114)
			(end 1.0922 -2.3114)
			(stroke
				(width 0)
				(type default)
			)
			(fill no)
			(layer "F.CrtYd")
		)
		(fp_poly
			(pts
				(xy -1.0922 -2.3114) (xy 1.0922 -2.3114) (xy 1.0922 2.3114) (xy -1.0922 2.3114)
			)
			(stroke
				(width 0)
				(type default)
			)
			(fill no)
			(layer "F.Fab")
		)
		(pad "1" smd rect
			(at 0 -1.397 270)
			(size 1.651 1.27)
			(layers "F.Cu" "F.Mask" "F.Paste")
			(net "P3V3_STBY")
		)
		(pad "2" smd rect
			(at 0 1.397 270)
			(size 1.651 1.27)
			(layers "F.Cu" "F.Mask" "F.Paste")
			(net "P3V3_STBY_OUT")
		)
	)
)
